# ZAIUS-LBB-EVT2-X01-BOM-X03-20161116.xls — DEPOP_GA (bom)
| FOXCONN TECHNOLOGY GROUP |  |  |  |  |  |  |  |  |  |  |  |  |
| BILL OF MATERIAL |  |  |  |  |  |  |  |  |  |  |  |  |
| REV OF  BOM |  | CUSTOMER | DELL |  | CUSTOMER P/N |  | PRODUCT CODE |  | PWA  REV |  | DATE |  |
| Sourcing (Single/Sole/Multi) | Critical Commodity (Y or N) | Component Class (1, 2, other) | Dell PSL (Y or N) | Item Number | Foxconn P/N | Dell P/N | Part Description | Manufacturer  Full Name | Manufacturer  Part Number | Qty | RoHS Status | Location |
